(kicad_pcb
	(version 20260206)
	(generator "pcbnew")
	(generator_version "10.0")
	(general
		(thickness 1.6)
		(legacy_teardrops no)
	)
	(paper "A4")
	(title_block
		(title "03242023_DA0F0TMBIJ0_F0T_Motherboard_J_brd_V01_OCP.brd")
		(comment 1 "Grand Teton / footprint 1301 of 6105 (J27), pads 225-291 of 291")
	)
	(layers
		(0 "F.Cu" signal "TOP")
		(4 "In1.Cu" signal "GND")
		(6 "In2.Cu" signal "IN1")
		(8 "In3.Cu" signal "GND1")
		(10 "In4.Cu" signal "IN2")
		(12 "In5.Cu" signal "GND2")
		(14 "In6.Cu" signal "IN3")
		(16 "In7.Cu" signal "GND3")
		(18 "In8.Cu" signal "VCC")
		(20 "In9.Cu" signal "VCC1")
		(22 "In10.Cu" signal "GND4")
		(24 "In11.Cu" signal "IN4")
		(26 "In12.Cu" signal "GND5")
		(28 "In13.Cu" signal "IN5")
		(30 "In14.Cu" signal "GND6")
		(32 "In15.Cu" signal "IN6")
		(34 "In16.Cu" signal "GND7")
		(2 "B.Cu" signal "BOTTOM")
		(9 "F.Adhes" user "F.Adhesive")
		(11 "B.Adhes" user "B.Adhesive")
		(13 "F.Paste" user "Package Geometry/Pastemask Top")
		(15 "B.Paste" user "Package Geometry/Pastemask Bottom")
		(5 "F.SilkS" user "Ref Des/Silkscreen Top")
		(7 "B.SilkS" user "Ref Des/Silkscreen Bottom")
		(1 "F.Mask" user "Board Geometry/Soldermask Top")
		(3 "B.Mask" user "Board Geometry/Soldermask Bottom")
		(17 "Dwgs.User" user "User.Drawings")
		(19 "Cmts.User" user "User.Comments")
		(21 "Eco1.User" user "User.Eco1")
		(23 "Eco2.User" user "User.Eco2")
		(25 "Edge.Cuts" user "Board Geometry/Outline")
		(27 "Margin" user)
		(31 "F.CrtYd" user "Package Geometry/Place Bound Top")
		(29 "B.CrtYd" user "Package Geometry/Place Bound Bottom")
		(35 "F.Fab" user "Ref Des/Assembly Top")
		(33 "B.Fab" user "Ref Des/Assembly Bottom")
	)
	(footprint ""
		(layer "F.Cu")
		(at 183.49468 -258.091686)
		(property "Reference" "J27"
			(at 2.19456 -81.755488 0)
			(unlocked yes)
			(layer "F.SilkS")
			(effects
				(font
					(size 0.7874 0.5842)
					(thickness 0.1524)
				)
				(justify left)
			)
		)
		(property "Value" ""
			(at 0 0 0)
			(layer "F.Fab")
			(effects
				(font
					(size 1.27 1.27)
				)
			)
		)
		(duplicate_pad_numbers_are_jumpers no)
		(pad "225" smd rect
			(at 2.050034 9.774936 270)
			(size 0.519938 1.4986)
			(layers "F.Cu" "F.Mask" "F.Paste")
			(net "M_F_CPU1_SB_CA<5>")
		)
		(pad "226" smd rect
			(at 2.050034 10.625074 270)
			(size 0.519938 1.4986)
			(layers "F.Cu" "F.Mask" "F.Paste")
			(net "GND")
		)
		(pad "227" smd rect
			(at 2.050034 11.474958 270)
			(size 0.519938 1.4986)
			(layers "F.Cu" "F.Mask" "F.Paste")
			(net "M_F_CPU1_SB_PAR")
		)
		(pad "228" smd rect
			(at 2.050034 12.325096 270)
			(size 0.519938 1.4986)
			(layers "F.Cu" "F.Mask" "F.Paste")
			(net "GND")
		)
		(pad "229" smd rect
			(at 2.050034 13.17498 270)
			(size 0.519938 1.4986)
			(layers "F.Cu" "F.Mask" "F.Paste")
			(net "M_F_CPU1_SB_CS_N<1>")
		)
		(pad "230" smd rect
			(at 2.050034 14.025118 270)
			(size 0.519938 1.4986)
			(layers "F.Cu" "F.Mask" "F.Paste")
			(net "GND")
		)
		(pad "231" smd rect
			(at 2.050034 14.875002 270)
			(size 0.519938 1.4986)
			(layers "F.Cu" "F.Mask" "F.Paste")
			(net "TP_CHF_CPU1_DIMM1_FRU_5")
		)
		(pad "232" smd rect
			(at 2.050034 15.724886 270)
			(size 0.519938 1.4986)
			(layers "F.Cu" "F.Mask" "F.Paste")
			(net "TP_CHF_CPU1_DIMM1_FRU_6")
		)
		(pad "233" smd rect
			(at 2.050034 16.575024 270)
			(size 0.519938 1.4986)
			(layers "F.Cu" "F.Mask" "F.Paste")
			(net "GND")
		)
		(pad "234" smd rect
			(at 2.050034 17.424908 270)
			(size 0.519938 1.4986)
			(layers "F.Cu" "F.Mask" "F.Paste")
			(net "M_F_CPU1_SB_CB<6>")
		)
		(pad "235" smd rect
			(at 2.050034 18.275046 270)
			(size 0.519938 1.4986)
			(layers "F.Cu" "F.Mask" "F.Paste")
			(net "GND")
		)
		(pad "236" smd rect
			(at 2.050034 19.12493 270)
			(size 0.519938 1.4986)
			(layers "F.Cu" "F.Mask" "F.Paste")
			(net "M_F_CPU1_SB_CB<7>")
		)
		(pad "237" smd rect
			(at 2.050034 19.975068 270)
			(size 0.519938 1.4986)
			(layers "F.Cu" "F.Mask" "F.Paste")
			(net "GND")
		)
		(pad "238" smd rect
			(at 2.050034 20.824952 270)
			(size 0.519938 1.4986)
			(layers "F.Cu" "F.Mask" "F.Paste")
			(net "M_F_CPU1_SB_DQS_DN<4>")
		)
		(pad "239" smd rect
			(at 2.050034 21.67509 270)
			(size 0.519938 1.4986)
			(layers "F.Cu" "F.Mask" "F.Paste")
			(net "M_F_CPU1_SB_DQS_DP<4>")
		)
		(pad "240" smd rect
			(at 2.050034 22.524974 270)
			(size 0.519938 1.4986)
			(layers "F.Cu" "F.Mask" "F.Paste")
			(net "GND")
		)
		(pad "241" smd rect
			(at 2.050034 23.375112 270)
			(size 0.519938 1.4986)
			(layers "F.Cu" "F.Mask" "F.Paste")
			(net "M_F_CPU1_SB_CB<2>")
		)
		(pad "242" smd rect
			(at 2.050034 24.224996 270)
			(size 0.519938 1.4986)
			(layers "F.Cu" "F.Mask" "F.Paste")
			(net "GND")
		)
		(pad "243" smd rect
			(at 2.050034 25.07488 270)
			(size 0.519938 1.4986)
			(layers "F.Cu" "F.Mask" "F.Paste")
			(net "M_F_CPU1_SB_CB<3>")
		)
		(pad "244" smd rect
			(at 2.050034 25.925018 270)
			(size 0.519938 1.4986)
			(layers "F.Cu" "F.Mask" "F.Paste")
			(net "GND")
		)
		(pad "245" smd rect
			(at 2.050034 26.774902 270)
			(size 0.519938 1.4986)
			(layers "F.Cu" "F.Mask" "F.Paste")
			(net "M_F_CPU1_SB_DQ<2>")
		)
		(pad "246" smd rect
			(at 2.050034 27.62504 270)
			(size 0.519938 1.4986)
			(layers "F.Cu" "F.Mask" "F.Paste")
			(net "GND")
		)
		(pad "247" smd rect
			(at 2.050034 28.474924 270)
			(size 0.519938 1.4986)
			(layers "F.Cu" "F.Mask" "F.Paste")
			(net "M_F_CPU1_SB_DQ<3>")
		)
		(pad "248" smd rect
			(at 2.050034 29.325062 270)
			(size 0.519938 1.4986)
			(layers "F.Cu" "F.Mask" "F.Paste")
			(net "GND")
		)
		(pad "249" smd rect
			(at 2.050034 30.174946 270)
			(size 0.519938 1.4986)
			(layers "F.Cu" "F.Mask" "F.Paste")
			(net "M_F_CPU1_SB_DQS_DN<5>")
		)
		(pad "250" smd rect
			(at 2.050034 31.025084 270)
			(size 0.519938 1.4986)
			(layers "F.Cu" "F.Mask" "F.Paste")
			(net "M_F_CPU1_SB_DQS_DP<5>")
		)
		(pad "251" smd rect
			(at 2.050034 31.874968 270)
			(size 0.519938 1.4986)
			(layers "F.Cu" "F.Mask" "F.Paste")
			(net "GND")
		)
		(pad "252" smd rect
			(at 2.050034 32.725106 270)
			(size 0.519938 1.4986)
			(layers "F.Cu" "F.Mask" "F.Paste")
			(net "M_F_CPU1_SB_DQ<6>")
		)
		(pad "253" smd rect
			(at 2.050034 33.57499 270)
			(size 0.519938 1.4986)
			(layers "F.Cu" "F.Mask" "F.Paste")
			(net "GND")
		)
		(pad "254" smd rect
			(at 2.050034 34.425128 270)
			(size 0.519938 1.4986)
			(layers "F.Cu" "F.Mask" "F.Paste")
			(net "M_F_CPU1_SB_DQ<7>")
		)
		(pad "255" smd rect
			(at 2.050034 35.275012 270)
			(size 0.519938 1.4986)
			(layers "F.Cu" "F.Mask" "F.Paste")
			(net "GND")
		)
		(pad "256" smd rect
			(at 2.050034 36.124896 270)
			(size 0.519938 1.4986)
			(layers "F.Cu" "F.Mask" "F.Paste")
			(net "M_F_CPU1_SB_DQ<10>")
		)
		(pad "257" smd rect
			(at 2.050034 36.975034 270)
			(size 0.519938 1.4986)
			(layers "F.Cu" "F.Mask" "F.Paste")
			(net "GND")
		)
		(pad "258" smd rect
			(at 2.050034 37.824918 270)
			(size 0.519938 1.4986)
			(layers "F.Cu" "F.Mask" "F.Paste")
			(net "M_F_CPU1_SB_DQ<11>")
		)
		(pad "259" smd rect
			(at 2.050034 38.675056 270)
			(size 0.519938 1.4986)
			(layers "F.Cu" "F.Mask" "F.Paste")
			(net "GND")
		)
		(pad "260" smd rect
			(at 2.050034 39.52494 270)
			(size 0.519938 1.4986)
			(layers "F.Cu" "F.Mask" "F.Paste")
			(net "M_F_CPU1_SB_DQS_DN<6>")
		)
		(pad "261" smd rect
			(at 2.050034 40.375078 270)
			(size 0.519938 1.4986)
			(layers "F.Cu" "F.Mask" "F.Paste")
			(net "M_F_CPU1_SB_DQS_DP<6>")
		)
		(pad "262" smd rect
			(at 2.050034 41.224962 270)
			(size 0.519938 1.4986)
			(layers "F.Cu" "F.Mask" "F.Paste")
			(net "GND")
		)
		(pad "263" smd rect
			(at 2.050034 42.0751 270)
			(size 0.519938 1.4986)
			(layers "F.Cu" "F.Mask" "F.Paste")
			(net "M_F_CPU1_SB_DQ<14>")
		)
		(pad "264" smd rect
			(at 2.050034 42.924984 270)
			(size 0.519938 1.4986)
			(layers "F.Cu" "F.Mask" "F.Paste")
			(net "GND")
		)
		(pad "265" smd rect
			(at 2.050034 43.775122 270)
			(size 0.519938 1.4986)
			(layers "F.Cu" "F.Mask" "F.Paste")
			(net "M_F_CPU1_SB_DQ<15>")
		)
		(pad "266" smd rect
			(at 2.050034 44.625006 270)
			(size 0.519938 1.4986)
			(layers "F.Cu" "F.Mask" "F.Paste")
			(net "GND")
		)
		(pad "267" smd rect
			(at 2.050034 45.47489 270)
			(size 0.519938 1.4986)
			(layers "F.Cu" "F.Mask" "F.Paste")
			(net "M_F_CPU1_SB_DQ<18>")
		)
		(pad "268" smd rect
			(at 2.050034 46.325028 270)
			(size 0.519938 1.4986)
			(layers "F.Cu" "F.Mask" "F.Paste")
			(net "GND")
		)
		(pad "269" smd rect
			(at 2.050034 47.174912 270)
			(size 0.519938 1.4986)
			(layers "F.Cu" "F.Mask" "F.Paste")
			(net "M_F_CPU1_SB_DQ<19>")
		)
		(pad "270" smd rect
			(at 2.050034 48.02505 270)
			(size 0.519938 1.4986)
			(layers "F.Cu" "F.Mask" "F.Paste")
			(net "GND")
		)
		(pad "271" smd rect
			(at 2.050034 48.874934 270)
			(size 0.519938 1.4986)
			(layers "F.Cu" "F.Mask" "F.Paste")
			(net "M_F_CPU1_SB_DQS_DN<7>")
		)
		(pad "272" smd rect
			(at 2.050034 49.725072 270)
			(size 0.519938 1.4986)
			(layers "F.Cu" "F.Mask" "F.Paste")
			(net "M_F_CPU1_SB_DQS_DP<7>")
		)
		(pad "273" smd rect
			(at 2.050034 50.574956 270)
			(size 0.519938 1.4986)
			(layers "F.Cu" "F.Mask" "F.Paste")
			(net "GND")
		)
		(pad "274" smd rect
			(at 2.050034 51.425094 270)
			(size 0.519938 1.4986)
			(layers "F.Cu" "F.Mask" "F.Paste")
			(net "M_F_CPU1_SB_DQ<22>")
		)
		(pad "275" smd rect
			(at 2.050034 52.274978 270)
			(size 0.519938 1.4986)
			(layers "F.Cu" "F.Mask" "F.Paste")
			(net "GND")
		)
		(pad "276" smd rect
			(at 2.050034 53.125116 270)
			(size 0.519938 1.4986)
			(layers "F.Cu" "F.Mask" "F.Paste")
			(net "M_F_CPU1_SB_DQ<23>")
		)
		(pad "277" smd rect
			(at 2.050034 53.975 270)
			(size 0.519938 1.4986)
			(layers "F.Cu" "F.Mask" "F.Paste")
			(net "GND")
		)
		(pad "278" smd rect
			(at 2.050034 54.824884 270)
			(size 0.519938 1.4986)
			(layers "F.Cu" "F.Mask" "F.Paste")
			(net "M_F_CPU1_SB_DQ<26>")
		)
		(pad "279" smd rect
			(at 2.050034 55.675022 270)
			(size 0.519938 1.4986)
			(layers "F.Cu" "F.Mask" "F.Paste")
			(net "GND")
		)
		(pad "280" smd rect
			(at 2.050034 56.524906 270)
			(size 0.519938 1.4986)
			(layers "F.Cu" "F.Mask" "F.Paste")
			(net "M_F_CPU1_SB_DQ<27>")
		)
		(pad "281" smd rect
			(at 2.050034 57.375044 270)
			(size 0.519938 1.4986)
			(layers "F.Cu" "F.Mask" "F.Paste")
			(net "GND")
		)
		(pad "282" smd rect
			(at 2.050034 58.224928 270)
			(size 0.519938 1.4986)
			(layers "F.Cu" "F.Mask" "F.Paste")
			(net "M_F_CPU1_SB_DQS_DN<8>")
		)
		(pad "283" smd rect
			(at 2.050034 59.075066 270)
			(size 0.519938 1.4986)
			(layers "F.Cu" "F.Mask" "F.Paste")
			(net "M_F_CPU1_SB_DQS_DP<8>")
		)
		(pad "284" smd rect
			(at 2.050034 59.92495 270)
			(size 0.519938 1.4986)
			(layers "F.Cu" "F.Mask" "F.Paste")
			(net "GND")
		)
		(pad "285" smd rect
			(at 2.050034 60.775088 270)
			(size 0.519938 1.4986)
			(layers "F.Cu" "F.Mask" "F.Paste")
			(net "M_F_CPU1_SB_DQ<30>")
		)
		(pad "286" smd rect
			(at 2.050034 61.624972 270)
			(size 0.519938 1.4986)
			(layers "F.Cu" "F.Mask" "F.Paste")
			(net "GND")
		)
		(pad "287" smd rect
			(at 2.050034 62.47511 270)
			(size 0.519938 1.4986)
			(layers "F.Cu" "F.Mask" "F.Paste")
			(net "M_F_CPU1_SB_DQ<31>")
		)
		(pad "288" smd rect
			(at 2.050034 63.324994 270)
			(size 0.519938 1.4986)
			(layers "F.Cu" "F.Mask" "F.Paste")
			(net "GND")
		)
		(pad "G1" thru_hole oval
			(at 0 -68.97497)
			(size 2.8194 1.5748)
			(drill oval 2.4384 1.1938)
			(layers "*.Cu" "*.Mask")
			(remove_unused_layers no)
			(net "GND")
			(clearance 0.127)
			(thermal_gap 0.127)
		)
		(pad "G2" thru_hole oval
			(at 0 3.875024)
			(size 2.8194 1.5748)
			(drill oval 2.4384 1.1938)
			(layers "*.Cu" "*.Mask")
			(remove_unused_layers no)
			(net "GND")
			(clearance 0.127)
			(thermal_gap 0.127)
		)
		(pad "G3" thru_hole oval
			(at 0 68.97497)
			(size 2.8194 1.5748)
			(drill oval 2.4384 1.1938)
			(layers "*.Cu" "*.Mask")
			(remove_unused_layers no)
			(net "GND")
			(clearance 0.127)
			(thermal_gap 0.127)
		)
	)
)
